(kicad_pcb
	(version 20260206)
	(generator "pcbnew")
	(generator_version "10.0")
	(general
		(thickness 0.77096)
		(legacy_teardrops no)
	)
	(paper "A4")
	(title_block
		(title "gnss-m2-neo-m9n — M2_NEO-M9N_MODULE.PcbDoc")
		(comment 1 "Time Appliance Project (Time Card) / footprints 27-32 of 40")
	)
	(layers
		(0 "F.Cu" signal "L01-Top Layer")
		(4 "In1.Cu" signal "L02-Inner Layer")
		(6 "In2.Cu" signal "L03-Inner Layer")
		(2 "B.Cu" signal "L04-Bottom Layer")
		(9 "F.Adhes" user "F.Adhesive")
		(11 "B.Adhes" user "B.Adhesive")
		(13 "F.Paste" user "Top Paste")
		(15 "B.Paste" user "Bottom Paste")
		(5 "F.SilkS" user "Top Overlay")
		(7 "B.SilkS" user "Bottom Overlay")
		(1 "F.Mask" user "Top Solder")
		(3 "B.Mask" user "Bottom Solder")
		(17 "Dwgs.User" user "User.Drawings")
		(19 "Cmts.User" user "User.Comments")
		(21 "Eco1.User" user "User.Eco1")
		(23 "Eco2.User" user "User.Eco2")
		(25 "Edge.Cuts" user)
		(27 "Margin" user)
		(31 "F.CrtYd" user "Top Courtyard")
		(29 "B.CrtYd" user "Bottom Courtyard")
		(35 "F.Fab" user "Top Component Outline")
		(33 "B.Fab" user "Bottom Component Outline 2")
	)
	(footprint "LotusSound:SOT23"
		(layer "F.Cu")
		(at 148.666305 90.4036 90)
		(property "Reference" "Q1"
			(at 2.477557 0.812595 0)
			(unlocked yes)
			(layer "F.SilkS")
			(effects
				(font
					(size 0.635 0.635)
					(thickness 0.1778)
				)
			)
		)
		(property "Value" "DMG2302UKQ-7"
			(at 7.883825 3.419602 90)
			(unlocked yes)
			(layer "F.SilkS")
			(hide yes)
			(effects
				(font
					(size 1.524 1.524)
					(thickness 0.254)
				)
			)
		)
		(sheetname "01-M2_NEO-M9N_MODULE")
		(sheetfile "01-M2_NEO-M9N_MODULE.kicad_sch")
		(duplicate_pad_numbers_are_jumpers no)
		(fp_line
			(start 0.5334 -1.8542)
			(end 0.5334 -0.9525)
			(stroke
				(width 0.1524)
				(type solid)
			)
			(layer "F.SilkS")
		)
		(fp_line
			(start -0.5334 -1.8542)
			(end 0.5334 -1.8542)
			(stroke
				(width 0.1524)
				(type solid)
			)
			(layer "F.SilkS")
		)
		(fp_line
			(start -0.5334 -1.8542)
			(end -0.5334 -0.9525)
			(stroke
				(width 0.1524)
				(type solid)
			)
			(layer "F.SilkS")
		)
		(fp_line
			(start 1.7526 -0.9525)
			(end 1.7526 0.9525)
			(stroke
				(width 0.1524)
				(type solid)
			)
			(layer "F.SilkS")
		)
		(fp_line
			(start 0.5334 -0.9525)
			(end 1.7526 -0.9525)
			(stroke
				(width 0.1524)
				(type solid)
			)
			(layer "F.SilkS")
		)
		(fp_line
			(start -1.7526 -0.9525)
			(end -0.5334 -0.9525)
			(stroke
				(width 0.1524)
				(type solid)
			)
			(layer "F.SilkS")
		)
		(fp_line
			(start -1.7526 -0.9525)
			(end -1.7526 0.9525)
			(stroke
				(width 0.1524)
				(type solid)
			)
			(layer "F.SilkS")
		)
		(fp_line
			(start 1.4484 0.9525)
			(end 1.7526 0.9525)
			(stroke
				(width 0.1524)
				(type solid)
			)
			(layer "F.SilkS")
		)
		(fp_line
			(start 1.4484 0.9525)
			(end 1.4484 1.8542)
			(stroke
				(width 0.1524)
				(type solid)
			)
			(layer "F.SilkS")
		)
		(fp_line
			(start -1.4484 0.9525)
			(end -1.4484 1.8542)
			(stroke
				(width 0.1524)
				(type solid)
			)
			(layer "F.SilkS")
		)
		(fp_line
			(start -1.7526 0.9525)
			(end -1.4484 0.9525)
			(stroke
				(width 0.1524)
				(type solid)
			)
			(layer "F.SilkS")
		)
		(fp_line
			(start -1.4484 1.8542)
			(end 1.4484 1.8542)
			(stroke
				(width 0.1524)
				(type solid)
			)
			(layer "F.SilkS")
		)
		(fp_circle
			(center -1.778 1.524)
			(end -1.7018 1.524)
			(stroke
				(width 0.1778)
				(type solid)
			)
			(fill no)
			(layer "F.SilkS")
		)
		(pad "1" smd rect
			(at -0.915 0.9652 90)
			(size 0.5588 1.27)
			(layers "F.Cu" "F.Mask" "F.Paste")
			(net "NetQ1_1")
		)
		(pad "2" smd rect
			(at 0.915 0.9652 90)
			(size 0.5588 1.27)
			(layers "F.Cu" "F.Mask" "F.Paste")
			(net "+3V3")
		)
		(pad "3" smd rect
			(at 0 -0.9652 90)
			(size 0.5588 1.27)
			(layers "F.Cu" "F.Mask" "F.Paste")
			(net "NetQ1_3")
		)
	)
	(footprint "MyLibrary:r0402"
		(layer "F.Cu")
		(at 142.701105 119.1036 -90)
		(property "Reference" "R8"
			(at -1.889255 0.022443 270)
			(unlocked yes)
			(layer "F.SilkS")
			(effects
				(font
					(size 0.635 0.635)
					(thickness 0.1778)
				)
			)
		)
		(property "Value" "0 ohm 0402"
			(at 2.907155 2.168983 270)
			(unlocked yes)
			(layer "F.SilkS")
			(hide yes)
			(effects
				(font
					(size 0.635 0.635)
					(thickness 0.1778)
				)
			)
		)
		(sheetname "01-M2_NEO-M9N_MODULE")
		(sheetfile "01-M2_NEO-M9N_MODULE.kicad_sch")
		(duplicate_pad_numbers_are_jumpers no)
		(fp_line
			(start -0.9906 0.5334)
			(end -0.9906 -0.5334)
			(stroke
				(width 0.1778)
				(type solid)
			)
			(layer "F.SilkS")
		)
		(fp_line
			(start 0.9906 0.5334)
			(end -0.9906 0.5334)
			(stroke
				(width 0.1778)
				(type solid)
			)
			(layer "F.SilkS")
		)
		(fp_line
			(start 0.9906 0.5334)
			(end 0.9906 -0.5334)
			(stroke
				(width 0.1778)
				(type solid)
			)
			(layer "F.SilkS")
		)
		(fp_line
			(start 0.9906 -0.5334)
			(end -0.9906 -0.5334)
			(stroke
				(width 0.1778)
				(type solid)
			)
			(layer "F.SilkS")
		)
		(pad "1" smd rect
			(at -0.5 0 270)
			(size 0.5 0.6)
			(layers "F.Cu" "F.Mask" "F.Paste")
			(net "TX_GPS")
		)
		(pad "2" smd rect
			(at 0.5 0 270)
			(size 0.5 0.6)
			(layers "F.Cu" "F.Mask" "F.Paste")
			(net "TX_GPS_CONN")
		)
	)
	(footprint "Vault:RESC1005X40X25LL05T10"
		(layer "F.Cu")
		(at 147.701105 112.7036 -90)
		(property "Reference" "R11"
			(at 1.6 0.195704 90)
			(unlocked yes)
			(layer "F.SilkS")
			(effects
				(font
					(face "Arial")
					(size 0.48006 0.48006)
					(thickness 0.254)
				)
			)
		)
		(property "Value" "10K_5%_0402"
			(at -2.606802 8.214275 180)
			(unlocked yes)
			(layer "F.SilkS")
			(hide yes)
			(effects
				(font
					(size 1.524 1.524)
					(thickness 0.254)
				)
			)
		)
		(sheetname "01-M2_NEO-M9N_MODULE")
		(sheetfile "01-M2_NEO-M9N_MODULE.kicad_sch")
		(duplicate_pad_numbers_are_jumpers no)
		(fp_line
			(start -0.75 0.4)
			(end -0.75 -0.4)
			(stroke
				(width 0.05)
				(type solid)
			)
			(layer "F.CrtYd")
		)
		(fp_line
			(start 0.75 0.4)
			(end -0.75 0.4)
			(stroke
				(width 0.05)
				(type solid)
			)
			(layer "F.CrtYd")
		)
		(fp_line
			(start 0.75 0.4)
			(end 0.75 -0.4)
			(stroke
				(width 0.05)
				(type solid)
			)
			(layer "F.CrtYd")
		)
		(fp_line
			(start 0 0.275)
			(end 0 -0.275)
			(stroke
				(width 0.1)
				(type solid)
			)
			(layer "F.CrtYd")
		)
		(fp_line
			(start 0.275 0)
			(end -0.275 0)
			(stroke
				(width 0.1)
				(type solid)
			)
			(layer "F.CrtYd")
		)
		(fp_line
			(start 0.75 -0.4)
			(end -0.75 -0.4)
			(stroke
				(width 0.05)
				(type solid)
			)
			(layer "F.CrtYd")
		)
		(pad "1" smd rect
			(at -0.375 0)
			(size 0.45 0.5)
			(layers "F.Cu" "F.Mask" "F.Paste")
			(net "SDA")
		)
		(pad "2" smd rect
			(at 0.375 0)
			(size 0.45 0.5)
			(layers "F.Cu" "F.Mask" "F.Paste")
			(net "+3V3")
		)
	)
	(footprint "MyLibrary:TP1MM"
		(layer "F.Cu")
		(at 149.301105 93.5036)
		(property "Reference" "TP4"
			(at 1.630785 -0.332727 0)
			(unlocked yes)
			(layer "F.SilkS")
			(effects
				(font
					(size 0.635 0.635)
					(thickness 0.1778)
				)
			)
		)
		(property "Value" "1MM"
			(at -2.092793 1.790085 270)
			(unlocked yes)
			(layer "F.SilkS")
			(hide yes)
			(effects
				(font
					(size 0.635 0.635)
					(thickness 0.1778)
				)
			)
		)
		(sheetname "01-M2_NEO-M9N_MODULE")
		(sheetfile "01-M2_NEO-M9N_MODULE.kicad_sch")
		(duplicate_pad_numbers_are_jumpers no)
		(pad "1" smd circle
			(at 0 0)
			(size 1 1)
			(layers "F.Cu" "F.Mask" "F.Paste")
			(net "VDD_USB")
			(solder_paste_margin -100)
			(thermal_bridge_angle 90)
		)
	)
	(footprint "MyLibrary:r0402"
		(layer "F.Cu")
		(at 156.501105 92.0036 -90)
		(property "Reference" "R10"
			(at 0.227805 -1.377557 270)
			(unlocked yes)
			(layer "F.SilkS")
			(effects
				(font
					(size 0.635 0.635)
					(thickness 0.1778)
				)
			)
		)
		(property "Value" "DNI 0 ohm 0402"
			(at 2.90715 2.168983 270)
			(unlocked yes)
			(layer "F.SilkS")
			(hide yes)
			(effects
				(font
					(size 0.635 0.635)
					(thickness 0.1778)
				)
			)
		)
		(sheetname "01-M2_NEO-M9N_MODULE")
		(sheetfile "01-M2_NEO-M9N_MODULE.kicad_sch")
		(duplicate_pad_numbers_are_jumpers no)
		(fp_line
			(start -0.9906 0.5334)
			(end -0.9906 -0.5334)
			(stroke
				(width 0.1778)
				(type solid)
			)
			(layer "F.SilkS")
		)
		(fp_line
			(start 0.9906 0.5334)
			(end -0.9906 0.5334)
			(stroke
				(width 0.1778)
				(type solid)
			)
			(layer "F.SilkS")
		)
		(fp_line
			(start 0.9906 0.5334)
			(end 0.9906 -0.5334)
			(stroke
				(width 0.1778)
				(type solid)
			)
			(layer "F.SilkS")
		)
		(fp_line
			(start 0.9906 -0.5334)
			(end -0.9906 -0.5334)
			(stroke
				(width 0.1778)
				(type solid)
			)
			(layer "F.SilkS")
		)
		(pad "1" smd rect
			(at -0.5 0 270)
			(size 0.5 0.6)
			(layers "F.Cu" "F.Mask" "F.Paste")
			(net "GND")
		)
		(pad "2" smd rect
			(at 0.5 0 270)
			(size 0.5 0.6)
			(layers "F.Cu" "F.Mask" "F.Paste")
			(net "D_SEL")
		)
	)
	(footprint "MyLibrary:led0603"
		(layer "F.Cu")
		(at 149.501105 117.2036)
		(property "Reference" "LED2"
			(at 0.3278 1.322443 0)
			(unlocked yes)
			(layer "F.SilkS")
			(effects
				(font
					(size 0.635 0.635)
					(thickness 0.1778)
				)
			)
		)
		(property "Value" "Green"
			(at -3.032583 3.262745 270)
			(unlocked yes)
			(layer "F.SilkS")
			(hide yes)
			(effects
				(font
					(size 0.635 0.635)
					(thickness 0.1778)
				)
			)
		)
		(sheetname "01-M2_NEO-M9N_MODULE")
		(sheetfile "01-M2_NEO-M9N_MODULE.kicad_sch")
		(duplicate_pad_numbers_are_jumpers no)
		(fp_line
			(start -1.397 -0.635)
			(end 1.397 -0.635)
			(stroke
				(width 0.1778)
				(type solid)
			)
			(layer "F.SilkS")
		)
		(fp_line
			(start -1.397 0.635)
			(end -1.397 -0.635)
			(stroke
				(width 0.1778)
				(type solid)
			)
			(layer "F.SilkS")
		)
		(fp_line
			(start -1.397 0.635)
			(end 1.397 0.635)
			(stroke
				(width 0.1778)
				(type solid)
			)
			(layer "F.SilkS")
		)
		(fp_line
			(start -0.03175 -0.12065)
			(end 0.08255 -0.00635)
			(stroke
				(width 0.0762)
				(type solid)
			)
			(layer "F.SilkS")
		)
		(fp_line
			(start -0.03175 0.10795)
			(end -0.03175 -0.12065)
			(stroke
				(width 0.0762)
				(type solid)
			)
			(layer "F.SilkS")
		)
		(fp_line
			(start -0.03175 0.10795)
			(end 0.08255 -0.00635)
			(stroke
				(width 0.0762)
				(type solid)
			)
			(layer "F.SilkS")
		)
		(fp_line
			(start 1.397 0.635)
			(end 1.397 -0.635)
			(stroke
				(width 0.1778)
				(type solid)
			)
			(layer "F.SilkS")
		)
		(fp_rect
			(start -0.03203 0.04819)
			(end 0.03705 -0.05276)
			(stroke
				(width 0)
				(type default)
			)
			(fill yes)
			(layer "F.SilkS")
		)
		(pad "1" smd rect
			(at -0.75 0)
			(size 0.8 0.8)
			(layers "F.Cu" "F.Mask" "F.Paste")
			(net "+3V3")
		)
		(pad "2" smd rect
			(at 0.75 0)
			(size 0.8 0.8)
			(layers "F.Cu" "F.Mask" "F.Paste")
			(net "NetLED2_2")
		)
	)
)
